(kicad_pcb
	(version 20260206)
	(generator "pcbnew")
	(generator_version "10.0")
	(general
		(thickness 1.6)
		(legacy_teardrops no)
	)
	(paper "A4")
	(title_block
		(title "Bryce Canyon_IOM_M2_16342-2_OCP.brd")
		(comment 1 "Bryce Canyon / footprints 22-27 of 1146")
	)
	(layers
		(0 "F.Cu" signal "TOP")
		(4 "In1.Cu" signal "L2GND")
		(6 "In2.Cu" signal "L3")
		(8 "In3.Cu" signal "L4VCC")
		(10 "In4.Cu" signal "L5VCC")
		(12 "In5.Cu" signal "L6")
		(14 "In6.Cu" signal "L7GND")
		(2 "B.Cu" signal "BOTTOM")
		(9 "F.Adhes" user "F.Adhesive")
		(11 "B.Adhes" user "B.Adhesive")
		(13 "F.Paste" user "Package Geometry/Pastemask Top")
		(15 "B.Paste" user "Package Geometry/Pastemask Bottom")
		(5 "F.SilkS" user "Ref Des/Silkscreen Top")
		(7 "B.SilkS" user "Ref Des/Silkscreen Bottom")
		(1 "F.Mask" user "Board Geometry/Soldermask Top")
		(3 "B.Mask" user "Board Geometry/Soldermask Bottom")
		(17 "Dwgs.User" user "User.Drawings")
		(19 "Cmts.User" user "User.Comments")
		(21 "Eco1.User" user "User.Eco1")
		(23 "Eco2.User" user "User.Eco2")
		(25 "Edge.Cuts" user "Board Geometry/Outline")
		(27 "Margin" user)
		(31 "F.CrtYd" user "Package Geometry/Place Bound Top")
		(29 "B.CrtYd" user "Package Geometry/Place Bound Bottom")
		(35 "F.Fab" user "Ref Des/Assembly Top")
		(33 "B.Fab" user "Ref Des/Assembly Bottom")
	)
	(footprint ""
		(layer "F.Cu")
		(at 222.499936 -120.000014)
		(property "Reference" ""
			(at 0 0 0)
			(layer "F.SilkS")
			(hide yes)
			(effects
				(font
					(size 1.27 1.27)
				)
			)
		)
		(property "Value" "*"
			(at -6.38175 0.19685 0)
			(unlocked yes)
			(layer "F.Fab")
			(hide yes)
			(effects
				(font
					(size 1.016 1.016)
					(thickness 0.1524)
				)
			)
		)
		(duplicate_pad_numbers_are_jumpers no)
		(fp_poly
			(pts
				(arc
					(start 5.0673 0)
					(mid -5.0673 0)
					(end 5.0673 0)
				)
			)
			(stroke
				(width 0)
				(type default)
			)
			(fill no)
			(layer "B.CrtYd")
		)
		(fp_poly
			(pts
				(arc
					(start 5.0673 0)
					(mid -5.0673 0)
					(end 5.0673 0)
				)
			)
			(stroke
				(width 0)
				(type default)
			)
			(fill no)
			(layer "F.CrtYd")
		)
		(fp_poly
			(pts
				(arc
					(start 5.0673 0)
					(mid -5.0673 0)
					(end 5.0673 0)
				)
			)
			(stroke
				(width 0)
				(type default)
			)
			(fill no)
			(layer "B.Fab")
		)
		(fp_poly
			(pts
				(arc
					(start 5.0673 0)
					(mid -5.0673 0)
					(end 5.0673 0)
				)
			)
			(stroke
				(width 0)
				(type default)
			)
			(fill no)
			(layer "F.Fab")
		)
		(pad "1" thru_hole circle
			(at 0 0)
			(size 9.525 9.525)
			(drill 3.5052)
			(layers "*.Cu" "*.Mask")
			(remove_unused_layers no)
			(net "Net_37")
			(clearance -2.5019)
			(thermal_gap 0.3048)
			(padstack
				(mode front_inner_back)
				(layer "Inner"
					(shape circle)
					(size 3.9116 3.9116)
					(clearance 0.3048)
				)
				(layer "B.Cu"
					(shape circle)
					(size 9.525 9.525)
					(clearance -2.5019)
				)
			)
		)
	)
	(footprint ""
		(layer "F.Cu")
		(at 75.632818 -148.365972 180)
		(property "Reference" "C75"
			(at 0 0 180)
			(layer "F.SilkS")
			(hide yes)
			(effects
				(font
					(size 1.27 1.27)
				)
			)
		)
		(property "Value" "SCD1U16V2KX-3GP"
			(at 1.1811 -2.7051 180)
			(unlocked yes)
			(layer "F.Fab")
			(hide yes)
			(effects
				(font
					(size 1.016 1.016)
					(thickness 0.1524)
				)
			)
		)
		(property "Device Type" "C402H22"
			(at 1.1811 -4.2291 180)
			(unlocked yes)
			(layer "F.Fab")
			(hide yes)
			(effects
				(font
					(size 1.016 1.016)
					(thickness 0.1524)
				)
			)
		)
		(duplicate_pad_numbers_are_jumpers no)
		(fp_rect
			(start -0.4318 0.9525)
			(end 0.4318 -0.9525)
			(stroke
				(width 0)
				(type default)
			)
			(fill no)
			(layer "F.CrtYd")
		)
		(fp_rect
			(start -0.4318 0.9525)
			(end 0.4318 -0.9525)
			(stroke
				(width 0)
				(type default)
			)
			(fill no)
			(layer "F.Fab")
		)
		(pad "1" smd custom
			(at 0 -0.4445 180)
			(size 0.1524 0.1524)
			(layers "F.Cu" "F.Mask" "F.Paste")
			(net "P3V3_STBY")
			(options
				(clearance outline)
				(anchor circle)
			)
			(primitives
				(gr_poly
					(pts
						(arc
							(start 0.3048 -0.2032)
							(mid 0.275042 -0.275042)
							(end 0.2032 -0.3048)
						)
						(arc
							(start -0.2032 -0.3048)
							(mid -0.275042 -0.275042)
							(end -0.3048 -0.2032)
						)
						(arc
							(start -0.3048 0.2032)
							(mid -0.275042 0.275042)
							(end -0.2032 0.3048)
						)
						(arc
							(start 0.2032 0.3048)
							(mid 0.275042 0.275042)
							(end 0.3048 0.2032)
						)
					)
					(width 0)
					(fill yes)
				)
			)
		)
		(pad "2" smd custom
			(at 0 0.4445 180)
			(size 0.1524 0.1524)
			(layers "F.Cu" "F.Mask" "F.Paste")
			(net "GND")
			(options
				(clearance outline)
				(anchor circle)
			)
			(primitives
				(gr_poly
					(pts
						(arc
							(start 0.3048 -0.2032)
							(mid 0.275042 -0.275042)
							(end 0.2032 -0.3048)
						)
						(arc
							(start -0.2032 -0.3048)
							(mid -0.275042 -0.275042)
							(end -0.3048 -0.2032)
						)
						(arc
							(start -0.3048 0.2032)
							(mid -0.275042 0.275042)
							(end -0.2032 0.3048)
						)
						(arc
							(start 0.2032 0.3048)
							(mid 0.275042 0.275042)
							(end 0.3048 0.2032)
						)
					)
					(width 0)
					(fill yes)
				)
			)
		)
	)
	(footprint ""
		(layer "F.Cu")
		(at 99.3902 -152.7302 -90)
		(property "Reference" "R31"
			(at 0 0 270)
			(layer "F.SilkS")
			(hide yes)
			(effects
				(font
					(size 1.27 1.27)
				)
			)
		)
		(property "Value" "4K7R2F-GP"
			(at 0.064008 -3.993896 270)
			(unlocked yes)
			(layer "F.Fab")
			(hide yes)
			(effects
				(font
					(size 1.016 1.016)
					(thickness 0.1524)
				)
			)
		)
		(property "Device Type" "R402H16"
			(at 0.064008 -5.517896 270)
			(unlocked yes)
			(layer "F.Fab")
			(hide yes)
			(effects
				(font
					(size 1.016 1.016)
					(thickness 0.1524)
				)
			)
		)
		(duplicate_pad_numbers_are_jumpers no)
		(fp_line
			(start -0.508 -0.9398)
			(end -0.508 0.9398)
			(stroke
				(width 0.1524)
				(type default)
			)
			(layer "F.SilkS")
		)
		(fp_line
			(start 0.508 -0.9398)
			(end -0.508 -0.9398)
			(stroke
				(width 0.1524)
				(type default)
			)
			(layer "F.SilkS")
		)
		(fp_rect
			(start -0.508 0.9398)
			(end 0.508 -0.9398)
			(stroke
				(width 0)
				(type default)
			)
			(fill no)
			(layer "F.CrtYd")
		)
		(fp_rect
			(start -0.508 0.9398)
			(end 0.508 -0.9398)
			(stroke
				(width 0)
				(type default)
			)
			(fill no)
			(layer "F.Fab")
		)
		(pad "1" smd custom
			(at 0 -0.4445 270)
			(size 0.1397 0.1397)
			(layers "F.Cu" "F.Mask" "F.Paste")
			(net "P3V3_STBY")
			(options
				(clearance outline)
				(anchor circle)
			)
			(primitives
				(gr_poly
					(pts
						(arc
							(start -0.1778 -0.2794)
							(mid -0.249642 -0.249642)
							(end -0.2794 -0.1778)
						)
						(arc
							(start -0.2794 0.1778)
							(mid -0.249642 0.249642)
							(end -0.1778 0.2794)
						)
						(arc
							(start 0.1778 0.2794)
							(mid 0.249642 0.249642)
							(end 0.2794 0.1778)
						)
						(arc
							(start 0.2794 -0.1778)
							(mid 0.249642 -0.249642)
							(end 0.1778 -0.2794)
						)
					)
					(width 0)
					(fill yes)
				)
			)
		)
		(pad "2" smd custom
			(at 0 0.4445 270)
			(size 0.1397 0.1397)
			(layers "F.Cu" "F.Mask" "F.Paste")
			(net "USB_OCS_N4")
			(options
				(clearance outline)
				(anchor circle)
			)
			(primitives
				(gr_poly
					(pts
						(arc
							(start -0.1778 -0.2794)
							(mid -0.249642 -0.249642)
							(end -0.2794 -0.1778)
						)
						(arc
							(start -0.2794 0.1778)
							(mid -0.249642 0.249642)
							(end -0.1778 0.2794)
						)
						(arc
							(start 0.1778 0.2794)
							(mid 0.249642 0.249642)
							(end 0.2794 0.1778)
						)
						(arc
							(start 0.2794 -0.1778)
							(mid 0.249642 -0.249642)
							(end 0.1778 -0.2794)
						)
					)
					(width 0)
					(fill yes)
				)
			)
		)
	)
	(footprint ""
		(layer "F.Cu")
		(at 36.28771 -121.3612 -90)
		(property "Reference" "SKT1"
			(at 0 0 270)
			(layer "F.SilkS")
			(hide yes)
			(effects
				(font
					(size 1.27 1.27)
				)
			)
		)
		(property "Value" "SKT-SPI16P-GP-U"
			(at -8.9916 4.641596 270)
			(unlocked yes)
			(layer "F.Fab")
			(hide yes)
			(effects
				(font
					(size 1.016 1.016)
					(thickness 0.1524)
				)
			)
		)
		(property "Device Type" "SKT-SOIC16-153139H258"
			(at -8.9916 3.117596 270)
			(unlocked yes)
			(layer "F.Fab")
			(hide yes)
			(effects
				(font
					(size 1.016 1.016)
					(thickness 0.1524)
				)
			)
		)
		(duplicate_pad_numbers_are_jumpers no)
		(fp_line
			(start -7.8994 6.4008)
			(end 7.8994 6.4008)
			(stroke
				(width 0.1524)
				(type default)
			)
			(layer "F.SilkS")
		)
		(fp_line
			(start 7.8994 6.4008)
			(end 7.8994 -6.4008)
			(stroke
				(width 0.1524)
				(type default)
			)
			(layer "F.SilkS")
		)
		(fp_line
			(start 6.7183 0.0762)
			(end 7.8994 1.2573)
			(stroke
				(width 0.1524)
				(type default)
			)
			(layer "F.SilkS")
		)
		(fp_line
			(start 7.8867 -1.0922)
			(end 6.7183 0.0762)
			(stroke
				(width 0.1524)
				(type default)
			)
			(layer "F.SilkS")
		)
		(fp_line
			(start 7.7216 -6.223)
			(end 7.7216 -3.6576)
			(stroke
				(width 0.508)
				(type default)
			)
			(layer "F.SilkS")
		)
		(fp_line
			(start -7.8994 -6.4008)
			(end -7.8994 6.4008)
			(stroke
				(width 0.1524)
				(type default)
			)
			(layer "F.SilkS")
		)
		(fp_line
			(start 7.8994 -6.4008)
			(end -7.8994 -6.4008)
			(stroke
				(width 0.1524)
				(type default)
			)
			(layer "F.SilkS")
		)
		(fp_poly
			(pts
				(xy -4.699 -3.855466) (xy -4.699 3.855466) (xy 4.699 3.855466) (xy 4.699 -3.855466)
			)
			(stroke
				(width 0)
				(type default)
			)
			(fill yes)
			(layer "F.SilkS")
		)
		(fp_rect
			(start -8.1534 11.6078)
			(end 8.1534 6.4008)
			(stroke
				(width 0)
				(type default)
			)
			(fill no)
			(layer "F.CrtYd")
		)
		(fp_rect
			(start -8.1534 -6.4008)
			(end 8.1534 -12.5222)
			(stroke
				(width 0)
				(type default)
			)
			(fill no)
			(layer "F.CrtYd")
		)
		(fp_poly
			(pts
				(xy -8.1534 6.4008) (xy -8.1534 -6.4008) (xy -6.2484 -6.4008) (xy -6.2484 -2.6416) (xy -7.6454 -2.6416)
				(xy -7.6454 2.6416) (xy -6.2484 2.6416) (xy -6.2484 6.4008)
			)
			(stroke
				(width 0)
				(type default)
			)
			(fill no)
			(layer "F.CrtYd")
		)
		(fp_poly
			(pts
				(xy 6.2484 -6.4008) (xy 8.1534 -6.4008) (xy 8.1534 6.4008) (xy 6.2484 6.4008) (xy 6.2484 2.6416)
				(xy 7.6454 2.6416) (xy 7.6454 -2.6416) (xy 6.2484 -2.6416)
			)
			(stroke
				(width 0)
				(type default)
			)
			(fill no)
			(layer "F.CrtYd")
		)
		(fp_poly
			(pts
				(xy 6.2484 -6.4008) (xy -6.2484 -6.4008) (xy -6.2484 -2.6416) (xy -7.6454 -2.6416) (xy -7.6454 2.6416)
				(xy -6.2484 2.6416) (xy -6.2484 6.4008) (xy 6.2484 6.4008) (xy 6.2484 2.6416) (xy 7.6454 2.6416)
				(xy 7.6454 -2.6416) (xy 6.2484 -2.6416)
			)
			(stroke
				(width 0)
				(type default)
			)
			(fill no)
			(layer "F.CrtYd")
		)
		(fp_rect
			(start -8.1534 11.6078)
			(end 8.1534 -12.5222)
			(stroke
				(width 0)
				(type default)
			)
			(fill no)
			(layer "F.Fab")
		)
		(pad "1" smd rect
			(at 4.445 -4.896866 270)
			(size 0.508 1.6764)
			(layers "F.Cu" "F.Mask" "F.Paste")
			(net "FLA0_SPI_HOLD_N")
		)
		(pad "2" smd rect
			(at 3.175 -4.896866 270)
			(size 0.508 1.6764)
			(layers "F.Cu" "F.Mask" "F.Paste")
			(net "P3V3_STBY")
		)
		(pad "3" smd rect
			(at 1.905 -4.896866 270)
			(size 0.508 1.6764)
			(layers "F.Cu" "F.Mask" "F.Paste")
			(net "FLA0_SPI_RST")
		)
		(pad "4" smd rect
			(at 0.635 -4.896866 270)
			(size 0.508 1.6764)
			(layers "F.Cu" "F.Mask" "F.Paste")
			(net "Net_927")
		)
		(pad "5" smd rect
			(at -0.635 -4.896866 270)
			(size 0.508 1.6764)
			(layers "F.Cu" "F.Mask" "F.Paste")
			(net "Net_926")
		)
		(pad "6" smd rect
			(at -1.905 -4.896866 270)
			(size 0.508 1.6764)
			(layers "F.Cu" "F.Mask" "F.Paste")
			(net "Net_925")
		)
		(pad "7" smd rect
			(at -3.175 -4.896866 270)
			(size 0.508 1.6764)
			(layers "F.Cu" "F.Mask" "F.Paste")
			(net "FLA_CS_0_R")
		)
		(pad "8" smd rect
			(at -4.445 -4.896866 270)
			(size 0.508 1.6764)
			(layers "F.Cu" "F.Mask" "F.Paste")
			(net "BMC_SPI_MISO_TPM")
		)
		(pad "9" smd rect
			(at -4.445 4.896866 270)
			(size 0.508 1.6764)
			(layers "F.Cu" "F.Mask" "F.Paste")
			(net "FLA0_WP_N")
		)
		(pad "10" smd rect
			(at -3.175 4.896866 270)
			(size 0.508 1.6764)
			(layers "F.Cu" "F.Mask" "F.Paste")
			(net "GND")
		)
		(pad "11" smd rect
			(at -1.905 4.896866 270)
			(size 0.508 1.6764)
			(layers "F.Cu" "F.Mask" "F.Paste")
			(net "Net_931")
		)
		(pad "12" smd rect
			(at -0.635 4.896866 270)
			(size 0.508 1.6764)
			(layers "F.Cu" "F.Mask" "F.Paste")
			(net "Net_930")
		)
		(pad "13" smd rect
			(at 0.635 4.896866 270)
			(size 0.508 1.6764)
			(layers "F.Cu" "F.Mask" "F.Paste")
			(net "Net_929")
		)
		(pad "14" smd rect
			(at 1.905 4.896866 270)
			(size 0.508 1.6764)
			(layers "F.Cu" "F.Mask" "F.Paste")
			(net "Net_928")
		)
		(pad "15" smd rect
			(at 3.175 4.896866 270)
			(size 0.508 1.6764)
			(layers "F.Cu" "F.Mask" "F.Paste")
			(net "BMC_SPI_MOSI_R")
		)
		(pad "16" smd rect
			(at 4.445 4.896866 270)
			(size 0.508 1.6764)
			(layers "F.Cu" "F.Mask" "F.Paste")
			(net "BMC_SPI_CLK_R")
		)
	)
	(footprint ""
		(layer "F.Cu")
		(at 61.04255 -144.404588 -90)
		(property "Reference" "R160"
			(at 0 0 270)
			(layer "F.SilkS")
			(hide yes)
			(effects
				(font
					(size 1.27 1.27)
				)
			)
		)
		(property "Value" "0R2J-2-GP"
			(at 0.064008 -3.993896 270)
			(unlocked yes)
			(layer "F.Fab")
			(hide yes)
			(effects
				(font
					(size 1.016 1.016)
					(thickness 0.1524)
				)
			)
		)
		(property "Device Type" "R402H16"
			(at 0.064008 -5.517896 270)
			(unlocked yes)
			(layer "F.Fab")
			(hide yes)
			(effects
				(font
					(size 1.016 1.016)
					(thickness 0.1524)
				)
			)
		)
		(duplicate_pad_numbers_are_jumpers no)
		(fp_line
			(start -0.508 -0.9398)
			(end -0.508 0.9398)
			(stroke
				(width 0.1524)
				(type default)
			)
			(layer "F.SilkS")
		)
		(fp_line
			(start 0.508 -0.9398)
			(end -0.508 -0.9398)
			(stroke
				(width 0.1524)
				(type default)
			)
			(layer "F.SilkS")
		)
		(fp_rect
			(start -0.508 0.9398)
			(end 0.508 -0.9398)
			(stroke
				(width 0)
				(type default)
			)
			(fill no)
			(layer "F.CrtYd")
		)
		(fp_rect
			(start -0.508 0.9398)
			(end 0.508 -0.9398)
			(stroke
				(width 0)
				(type default)
			)
			(fill no)
			(layer "F.Fab")
		)
		(pad "1" smd custom
			(at 0 -0.4445 270)
			(size 0.1397 0.1397)
			(layers "F.Cu" "F.Mask" "F.Paste")
			(net "I2C_SCC_SCL_OUT")
			(options
				(clearance outline)
				(anchor circle)
			)
			(primitives
				(gr_poly
					(pts
						(arc
							(start -0.1778 -0.2794)
							(mid -0.249642 -0.249642)
							(end -0.2794 -0.1778)
						)
						(arc
							(start -0.2794 0.1778)
							(mid -0.249642 0.249642)
							(end -0.1778 0.2794)
						)
						(arc
							(start 0.1778 0.2794)
							(mid 0.249642 0.249642)
							(end 0.2794 0.1778)
						)
						(arc
							(start 0.2794 -0.1778)
							(mid 0.249642 -0.249642)
							(end 0.1778 -0.2794)
						)
					)
					(width 0)
					(fill yes)
				)
			)
		)
		(pad "2" smd custom
			(at 0 0.4445 270)
			(size 0.1397 0.1397)
			(layers "F.Cu" "F.Mask" "F.Paste")
			(net "BMC_SMB3_CLK")
			(options
				(clearance outline)
				(anchor circle)
			)
			(primitives
				(gr_poly
					(pts
						(arc
							(start -0.1778 -0.2794)
							(mid -0.249642 -0.249642)
							(end -0.2794 -0.1778)
						)
						(arc
							(start -0.2794 0.1778)
							(mid -0.249642 0.249642)
							(end -0.1778 0.2794)
						)
						(arc
							(start 0.1778 0.2794)
							(mid 0.249642 0.249642)
							(end 0.2794 0.1778)
						)
						(arc
							(start 0.2794 -0.1778)
							(mid 0.249642 -0.249642)
							(end 0.1778 -0.2794)
						)
					)
					(width 0)
					(fill yes)
				)
			)
		)
	)
	(footprint ""
		(layer "F.Cu")
		(at 180.848 -111.0234)
		(property "Reference" "R545"
			(at 0 0 0)
			(layer "F.SilkS")
			(hide yes)
			(effects
				(font
					(size 1.27 1.27)
				)
			)
		)
		(property "Value" "4K7R2F-GP"
			(at 0.064008 -3.993896 0)
			(unlocked yes)
			(layer "F.Fab")
			(hide yes)
			(effects
				(font
					(size 1.016 1.016)
					(thickness 0.1524)
				)
			)
		)
		(property "Device Type" "R402H16"
			(at 0.064008 -5.517896 0)
			(unlocked yes)
			(layer "F.Fab")
			(hide yes)
			(effects
				(font
					(size 1.016 1.016)
					(thickness 0.1524)
				)
			)
		)
		(duplicate_pad_numbers_are_jumpers no)
		(fp_line
			(start -0.508 -0.9398)
			(end -0.508 0.9398)
			(stroke
				(width 0.1524)
				(type default)
			)
			(layer "F.SilkS")
		)
		(fp_line
			(start 0.508 -0.9398)
			(end -0.508 -0.9398)
			(stroke
				(width 0.1524)
				(type default)
			)
			(layer "F.SilkS")
		)
		(fp_rect
			(start -0.508 0.9398)
			(end 0.508 -0.9398)
			(stroke
				(width 0)
				(type default)
			)
			(fill no)
			(layer "F.CrtYd")
		)
		(fp_rect
			(start -0.508 0.9398)
			(end 0.508 -0.9398)
			(stroke
				(width 0)
				(type default)
			)
			(fill no)
			(layer "F.Fab")
		)
		(pad "1" smd custom
			(at 0 -0.4445)
			(size 0.1397 0.1397)
			(layers "F.Cu" "F.Mask" "F.Paste")
			(net "P3V3_STBY")
			(options
				(clearance outline)
				(anchor circle)
			)
			(primitives
				(gr_poly
					(pts
						(arc
							(start -0.1778 -0.2794)
							(mid -0.249642 -0.249642)
							(end -0.2794 -0.1778)
						)
						(arc
							(start -0.2794 0.1778)
							(mid -0.249642 0.249642)
							(end -0.1778 0.2794)
						)
						(arc
							(start 0.1778 0.2794)
							(mid 0.249642 0.249642)
							(end 0.2794 0.1778)
						)
						(arc
							(start 0.2794 -0.1778)
							(mid 0.249642 -0.249642)
							(end 0.1778 -0.2794)
						)
					)
					(width 0)
					(fill yes)
				)
			)
		)
		(pad "2" smd custom
			(at 0 0.4445)
			(size 0.1397 0.1397)
			(layers "F.Cu" "F.Mask" "F.Paste")
			(net "TEMP_1_A0")
			(options
				(clearance outline)
				(anchor circle)
			)
			(primitives
				(gr_poly
					(pts
						(arc
							(start -0.1778 -0.2794)
							(mid -0.249642 -0.249642)
							(end -0.2794 -0.1778)
						)
						(arc
							(start -0.2794 0.1778)
							(mid -0.249642 0.249642)
							(end -0.1778 0.2794)
						)
						(arc
							(start 0.1778 0.2794)
							(mid 0.249642 0.249642)
							(end 0.2794 0.1778)
						)
						(arc
							(start 0.2794 -0.1778)
							(mid 0.249642 -0.249642)
							(end 0.1778 -0.2794)
						)
					)
					(width 0)
					(fill yes)
				)
			)
		)
	)
)
